FILE_TYPE = MULTI_PHYS_TABLE;

PART 'MAX15090BEWIT'

{========================================================================================}
:VALUE            | PART_TYPE | MATERIAL | PART_NUMBER       = STANDARD        | LIFECYCLE      | PART_NUMBER       | JEDEC_TYPE                         | DESCRIPTION                                              | MANUFTR | MANUF_PN         | RD_CMPLS_LVL | CMPLS_LVL | FROM_PJ      | CLASS | DIP_SMD | DATA                     | EE_CHECK_LIST | FP_ECN               | PSL | CREATOR | STATUS | MSD | ESD_CDM | ESD_HBM | ESD_MM | PIN_LENGTH_SHORT_PIN | PIN_LENGTH_LONG_PIN | CREATEDAY  ;
{========================================================================================}
 'MAX15090BEWI+T' | 'SMLF'    | 'IC'     | 'AL015080B00'(!)  = ''              | ''             | 'AL015080B00'     |'BGA28_0-5_3-525X2-065'| 'IC OTHER(28P)MAX15090BEWI+T(WLP)'                       | 'MAM'   | 'MAX15090BEWI+T' | 'EP(V1)'     | ''        | 'UH3M-KEVIN' | 'IC'  | ''      | 'MAM_MAX15090BEWI+T.pdf' | ''            | ''                   | ''  | ''      | ''     | ''  | ''      | ''      | ''     | ''                   | ''                  | '20160324'
 'MAX15090BEWI+T' | 'SMLF'    | 'EMPTY'  | 'AL015080B00'(!)  = ''              | ''             | 'AL015080B00'     |'BGA28_0-5_3-525X2-065'| 'IC OTHER(28P)MAX15090BEWI+T(WLP)'                       | 'MAM'   | 'MAX15090BEWI+T' | 'EP(V1)'     | ''        | 'UH3M-KEVIN' | 'IC'  | ''      | 'MAM_MAX15090BEWI+T.pdf' | ''            | ''                   | ''  | ''      | ''     | ''  | ''      | ''      | ''     | ''                   | ''                  | '20160324'
 'MAX15090BEWI+T' | 'SMLF'    | 'IC'     | 'SP_AL015080B00'(!) = ''              | ''             | 'AL015080B00'     |'BGA28_0-5_3-525X2-065_SMDC9_SM13'| 'IC OTHER(28P)MAX15090BEWI+T(WLP) (PAD:9 SOLDERMASK:13)' | 'MAM'   | 'MAX15090BEWI+T' | 'EP(V1)'     | ''        | 'S8Z-IAN'    | 'IC'  | ''      | 'MAM_MAX15090BEWI+T.pdf' | ''            | 'MAX15090BEWI+T.msg' | ''  | ''      | ''     | ''  | ''      | ''      | ''     | ''                   | ''                  | '20201222'
 'MAX15090BEWI+T' | 'SMLF'    | 'EMPTY'  | 'SP_AL015080B00'(!) = ''              | ''             | 'AL015080B00'     |'BGA28_0-5_3-525X2-065_SMDC9_SM13'| 'IC OTHER(28P)MAX15090BEWI+T(WLP) (PAD:9 SOLDERMASK:13)' | 'MAM'   | 'MAX15090BEWI+T' | 'EP(V1)'     | ''        | 'S8Z-IAN'    | 'IC'  | ''      | 'MAM_MAX15090BEWI+T.pdf' | ''            | 'MAX15090BEWI+T.msg' | ''  | ''      | ''     | ''  | ''      | ''      | ''     | ''                   | ''                  | '20201222'
 'MAX15090BEWI+T' | 'SMLF'    | 'IC'     | 'AL015080B00SEL1'(!) = ''               | ''               | 'AL015080B00SEL1' |'BGA28_0-5_3-525X2-065_SMDC9_SM13'| 'IC(28P)MAX15090BEWI+T(WLP)SELASN'                       | 'MAM'   | 'MAX15090BEWI+T' | 'EP(V1)'     | ''        | 'UH3M-KEVIN' | 'IC'  | ''      | 'MAM_MAX15090BEWI+T.pdf' | ''            | 'SEL_15QPN.xlsx'     | ''  | ''      | ''     | ''  | ''      | ''      | ''     | ''                   | ''                  | '20230719'
 'MAX15090BEWI+T' | 'SMLF'    | 'EMPTY'  | 'AL015080B00SEL1'(!) = ''               | ''               | 'AL015080B00SEL1' |'BGA28_0-5_3-525X2-065_SMDC9_SM13'| 'IC(28P)MAX15090BEWI+T(WLP)SELASN'                       | 'MAM'   | 'MAX15090BEWI+T' | 'EP(V1)'     | ''        | 'UH3M-KEVIN' | 'IC'  | ''      | 'MAM_MAX15090BEWI+T.pdf' | ''            | 'SEL_15QPN.xlsx'     | ''  | ''      | ''     | ''  | ''      | ''      | ''     | ''                   | ''                  | '20230719'

END_PART

END.

